(kicad_pcb
	(version 20260206)
	(generator "pcbnew")
	(generator_version "10.0")
	(general
		(thickness 1.6)
		(legacy_teardrops no)
	)
	(paper "A4")
	(title_block
		(title "04192023_DAF0TMB3IC0_F0TG_MB_C_brd_V02_OCP.brd")
		(comment 1 "Grand Teton / footprints 878-885 of 8354")
	)
	(layers
		(0 "F.Cu" signal "TOP")
		(4 "In1.Cu" signal "GND")
		(6 "In2.Cu" signal "IN1")
		(8 "In3.Cu" signal "GND1")
		(10 "In4.Cu" signal "IN2")
		(12 "In5.Cu" signal "GND2")
		(14 "In6.Cu" signal "IN3")
		(16 "In7.Cu" signal "GND3")
		(18 "In8.Cu" signal "VCC")
		(20 "In9.Cu" signal "VCC1")
		(22 "In10.Cu" signal "GND4")
		(24 "In11.Cu" signal "IN4")
		(26 "In12.Cu" signal "GND5")
		(28 "In13.Cu" signal "IN5")
		(30 "In14.Cu" signal "GND6")
		(32 "In15.Cu" signal "IN6")
		(34 "In16.Cu" signal "GND7")
		(2 "B.Cu" signal "BOTTOM")
		(9 "F.Adhes" user "F.Adhesive")
		(11 "B.Adhes" user "B.Adhesive")
		(13 "F.Paste" user "Package Geometry/Pastemask Top")
		(15 "B.Paste" user "Package Geometry/Pastemask Bottom")
		(5 "F.SilkS" user "Ref Des/Silkscreen Top")
		(7 "B.SilkS" user "Ref Des/Silkscreen Bottom")
		(1 "F.Mask" user "Board Geometry/Soldermask Top")
		(3 "B.Mask" user "Board Geometry/Soldermask Bottom")
		(17 "Dwgs.User" user "User.Drawings")
		(19 "Cmts.User" user "User.Comments")
		(21 "Eco1.User" user "User.Eco1")
		(23 "Eco2.User" user "User.Eco2")
		(25 "Edge.Cuts" user "Board Geometry/Outline")
		(27 "Margin" user)
		(31 "F.CrtYd" user "Package Geometry/Place Bound Top")
		(29 "B.CrtYd" user "Package Geometry/Place Bound Bottom")
		(35 "F.Fab" user "Ref Des/Assembly Top")
		(33 "B.Fab" user "Ref Des/Assembly Bottom")
	)
	(footprint ""
		(layer "F.Cu")
		(at 257.501644 -139.718796 180)
		(property "Reference" "R606"
			(at 0 0 180)
			(layer "F.SilkS")
			(hide yes)
			(effects
				(font
					(size 1.27 1.27)
				)
			)
		)
		(property "Value" ""
			(at 0 0 180)
			(layer "F.Fab")
			(effects
				(font
					(size 1.27 1.27)
				)
			)
		)
		(duplicate_pad_numbers_are_jumpers no)
		(fp_line
			(start 0.7874 0.4064)
			(end -0.7874 0.4064)
			(stroke
				(width 0.1524)
				(type default)
			)
			(layer "F.SilkS")
		)
		(fp_line
			(start 0.7874 -0.4064)
			(end 0.7874 0.4064)
			(stroke
				(width 0.1524)
				(type default)
			)
			(layer "F.SilkS")
		)
		(fp_line
			(start -0.7874 0.4064)
			(end -0.7874 -0.4064)
			(stroke
				(width 0.1524)
				(type default)
			)
			(layer "F.SilkS")
		)
		(fp_line
			(start -0.7874 -0.4064)
			(end 0.7874 -0.4064)
			(stroke
				(width 0.1524)
				(type default)
			)
			(layer "F.SilkS")
		)
		(fp_line
			(start 0.67945 0.3048)
			(end 0.120396 0.3048)
			(stroke
				(width 0.1)
				(type default)
			)
			(layer "F.Fab")
		)
		(fp_line
			(start 0.67945 -0.3048)
			(end 0.67945 0.3048)
			(stroke
				(width 0.1)
				(type default)
			)
			(layer "F.Fab")
		)
		(fp_line
			(start 0.12065 -0.2794)
			(end 0.12065 -0.3048)
			(stroke
				(width 0.1)
				(type default)
			)
			(layer "F.Fab")
		)
		(fp_line
			(start 0.12065 -0.3048)
			(end 0.67945 -0.3048)
			(stroke
				(width 0.1)
				(type default)
			)
			(layer "F.Fab")
		)
		(fp_line
			(start 0.120396 0.3048)
			(end 0.120396 0.2794)
			(stroke
				(width 0.1)
				(type default)
			)
			(layer "F.Fab")
		)
		(fp_line
			(start 0.120396 0.2794)
			(end -0.12065 0.2794)
			(stroke
				(width 0.1)
				(type default)
			)
			(layer "F.Fab")
		)
		(fp_line
			(start -0.12065 0.3048)
			(end -0.67945 0.3048)
			(stroke
				(width 0.1)
				(type default)
			)
			(layer "F.Fab")
		)
		(fp_line
			(start -0.12065 0.2794)
			(end -0.12065 0.3048)
			(stroke
				(width 0.1)
				(type default)
			)
			(layer "F.Fab")
		)
		(fp_line
			(start -0.12065 -0.2794)
			(end 0.12065 -0.2794)
			(stroke
				(width 0.1)
				(type default)
			)
			(layer "F.Fab")
		)
		(fp_line
			(start -0.12065 -0.305054)
			(end -0.12065 -0.2794)
			(stroke
				(width 0.1)
				(type default)
			)
			(layer "F.Fab")
		)
		(fp_line
			(start -0.67945 0.3048)
			(end -0.67945 -0.305054)
			(stroke
				(width 0.1)
				(type default)
			)
			(layer "F.Fab")
		)
		(fp_line
			(start -0.67945 -0.305054)
			(end -0.12065 -0.305054)
			(stroke
				(width 0.1)
				(type default)
			)
			(layer "F.Fab")
		)
		(pad "1" smd circle
			(at -0.40005 0 180)
			(size 0 0)
			(layers "F.Cu" "F.Mask" "F.Paste")
			(net "SPI_CPU0_LVC3_D2")
		)
		(pad "2" smd circle
			(at 0.40005 0 180)
			(size 0 0)
			(layers "F.Cu" "F.Mask" "F.Paste")
			(net "SPI_CPU0_LVC3_SCM_D2")
		)
	)
	(footprint ""
		(layer "F.Cu")
		(at 236.649768 -272.50009)
		(property "Reference" "H100"
			(at -4.274566 -5.764276 0)
			(unlocked yes)
			(layer "F.SilkS")
			(effects
				(font
					(size 0.7874 0.5842)
					(thickness 0.1524)
				)
				(justify left)
			)
		)
		(property "Value" ""
			(at 0 0 0)
			(layer "F.Fab")
			(effects
				(font
					(size 1.27 1.27)
				)
			)
		)
		(duplicate_pad_numbers_are_jumpers no)
		(pad "1" thru_hole circle
			(at 0 0)
			(size 10.0076 10.0076)
			(drill 5.6134)
			(layers "*.Cu" "*.Mask")
			(remove_unused_layers no)
			(net "GND")
			(clearance -1.9431)
		)
	)
	(footprint ""
		(layer "F.Cu")
		(at 87.430102 -375.49963 -90)
		(property "Reference" "C727"
			(at 0 0 270)
			(layer "F.SilkS")
			(hide yes)
			(effects
				(font
					(size 1.27 1.27)
				)
			)
		)
		(property "Value" ""
			(at 0 0 270)
			(layer "F.Fab")
			(effects
				(font
					(size 1.27 1.27)
				)
			)
		)
		(duplicate_pad_numbers_are_jumpers no)
		(fp_line
			(start -0.299974 0.150114)
			(end -0.299974 -0.150114)
			(stroke
				(width 0.1)
				(type default)
			)
			(layer "F.Fab")
		)
		(fp_line
			(start 0.299974 0.150114)
			(end -0.299974 0.150114)
			(stroke
				(width 0.1)
				(type default)
			)
			(layer "F.Fab")
		)
		(fp_line
			(start -0.299974 -0.150114)
			(end 0.299974 -0.150114)
			(stroke
				(width 0.1)
				(type default)
			)
			(layer "F.Fab")
		)
		(fp_line
			(start 0.299974 -0.150114)
			(end 0.299974 0.150114)
			(stroke
				(width 0.1)
				(type default)
			)
			(layer "F.Fab")
		)
		(pad "1" smd rect
			(at -0.2667 0 270)
			(size 0.3048 0.381)
			(layers "F.Cu" "F.Mask" "F.Paste")
			(net "P5E_CPU1_P1_TX_C_DP<7>")
		)
		(pad "2" smd rect
			(at 0.2667 0 270)
			(size 0.3048 0.381)
			(layers "F.Cu" "F.Mask" "F.Paste")
			(net "P5E_CPU1_P1_TX_DP<7>")
		)
	)
	(footprint ""
		(layer "F.Cu")
		(at 109.549946 -54.882034 -90)
		(property "Reference" "R6306"
			(at 0 0 270)
			(layer "F.SilkS")
			(hide yes)
			(effects
				(font
					(size 1.27 1.27)
				)
			)
		)
		(property "Value" ""
			(at 0 0 270)
			(layer "F.Fab")
			(effects
				(font
					(size 1.27 1.27)
				)
			)
		)
		(duplicate_pad_numbers_are_jumpers no)
		(fp_line
			(start -0.7874 0.4064)
			(end -0.7874 -0.4064)
			(stroke
				(width 0.1524)
				(type default)
			)
			(layer "F.SilkS")
		)
		(fp_line
			(start 0.7874 0.4064)
			(end -0.7874 0.4064)
			(stroke
				(width 0.1524)
				(type default)
			)
			(layer "F.SilkS")
		)
		(fp_line
			(start -0.7874 -0.4064)
			(end 0.7874 -0.4064)
			(stroke
				(width 0.1524)
				(type default)
			)
			(layer "F.SilkS")
		)
		(fp_line
			(start 0.7874 -0.4064)
			(end 0.7874 0.4064)
			(stroke
				(width 0.1524)
				(type default)
			)
			(layer "F.SilkS")
		)
		(fp_line
			(start -0.67945 0.3048)
			(end -0.67945 -0.305054)
			(stroke
				(width 0.1)
				(type default)
			)
			(layer "F.Fab")
		)
		(fp_line
			(start -0.12065 0.3048)
			(end -0.67945 0.3048)
			(stroke
				(width 0.1)
				(type default)
			)
			(layer "F.Fab")
		)
		(fp_line
			(start 0.120396 0.3048)
			(end 0.120396 0.2794)
			(stroke
				(width 0.1)
				(type default)
			)
			(layer "F.Fab")
		)
		(fp_line
			(start 0.67945 0.3048)
			(end 0.120396 0.3048)
			(stroke
				(width 0.1)
				(type default)
			)
			(layer "F.Fab")
		)
		(fp_line
			(start -0.12065 0.2794)
			(end -0.12065 0.3048)
			(stroke
				(width 0.1)
				(type default)
			)
			(layer "F.Fab")
		)
		(fp_line
			(start 0.120396 0.2794)
			(end -0.12065 0.2794)
			(stroke
				(width 0.1)
				(type default)
			)
			(layer "F.Fab")
		)
		(fp_line
			(start -0.12065 -0.2794)
			(end 0.12065 -0.2794)
			(stroke
				(width 0.1)
				(type default)
			)
			(layer "F.Fab")
		)
		(fp_line
			(start 0.12065 -0.2794)
			(end 0.12065 -0.3048)
			(stroke
				(width 0.1)
				(type default)
			)
			(layer "F.Fab")
		)
		(fp_line
			(start 0.12065 -0.3048)
			(end 0.67945 -0.3048)
			(stroke
				(width 0.1)
				(type default)
			)
			(layer "F.Fab")
		)
		(fp_line
			(start 0.67945 -0.3048)
			(end 0.67945 0.3048)
			(stroke
				(width 0.1)
				(type default)
			)
			(layer "F.Fab")
		)
		(fp_line
			(start -0.67945 -0.305054)
			(end -0.12065 -0.305054)
			(stroke
				(width 0.1)
				(type default)
			)
			(layer "F.Fab")
		)
		(fp_line
			(start -0.12065 -0.305054)
			(end -0.12065 -0.2794)
			(stroke
				(width 0.1)
				(type default)
			)
			(layer "F.Fab")
		)
		(pad "1" smd circle
			(at -0.40005 0 270)
			(size 0 0)
			(layers "F.Cu" "F.Mask" "F.Paste")
			(net "P3V3_AUX")
		)
		(pad "2" smd circle
			(at 0.40005 0 270)
			(size 0 0)
			(layers "F.Cu" "F.Mask" "F.Paste")
			(net "USB_HUB2_TI_HS_SUSPEND")
		)
	)
	(footprint ""
		(layer "F.Cu")
		(at 401.183348 -16.100298 90)
		(property "Reference" "C1556"
			(at 0 0 90)
			(layer "F.SilkS")
			(hide yes)
			(effects
				(font
					(size 1.27 1.27)
				)
			)
		)
		(property "Value" ""
			(at 0 0 90)
			(layer "F.Fab")
			(effects
				(font
					(size 1.27 1.27)
				)
			)
		)
		(duplicate_pad_numbers_are_jumpers no)
		(fp_line
			(start 0.299974 -0.150114)
			(end 0.299974 0.150114)
			(stroke
				(width 0.1)
				(type default)
			)
			(layer "F.Fab")
		)
		(fp_line
			(start -0.299974 -0.150114)
			(end 0.299974 -0.150114)
			(stroke
				(width 0.1)
				(type default)
			)
			(layer "F.Fab")
		)
		(fp_line
			(start 0.299974 0.150114)
			(end -0.299974 0.150114)
			(stroke
				(width 0.1)
				(type default)
			)
			(layer "F.Fab")
		)
		(fp_line
			(start -0.299974 0.150114)
			(end -0.299974 -0.150114)
			(stroke
				(width 0.1)
				(type default)
			)
			(layer "F.Fab")
		)
		(pad "1" smd rect
			(at -0.2667 0 90)
			(size 0.3048 0.381)
			(layers "F.Cu" "F.Mask" "F.Paste")
			(net "P5E_CPU0_G3_TX_C_DN<11>")
		)
		(pad "2" smd rect
			(at 0.2667 0 90)
			(size 0.3048 0.381)
			(layers "F.Cu" "F.Mask" "F.Paste")
			(net "P5E_CPU0_G3_TX_DN<11>")
		)
	)
	(footprint ""
		(layer "F.Cu")
		(at 445.467994 -411.8991 180)
		(property "Reference" "PC6561"
			(at 2.745994 3.49123 0)
			(unlocked yes)
			(layer "F.SilkS")
			(effects
				(font
					(size 0.7874 0.5842)
					(thickness 0.1524)
				)
				(justify left)
			)
		)
		(property "Value" ""
			(at 0 0 180)
			(layer "F.Fab")
			(effects
				(font
					(size 1.27 1.27)
				)
			)
		)
		(duplicate_pad_numbers_are_jumpers no)
		(fp_line
			(start 2.750058 2.750058)
			(end 2.750058 0.9398)
			(stroke
				(width 0.1524)
				(type default)
			)
			(layer "F.SilkS")
		)
		(fp_line
			(start 2.750058 -0.9398)
			(end 2.750058 -2.750058)
			(stroke
				(width 0.1524)
				(type default)
			)
			(layer "F.SilkS")
		)
		(fp_line
			(start 2.750058 -2.750058)
			(end -1.988058 -2.750058)
			(stroke
				(width 0.1524)
				(type default)
			)
			(layer "F.SilkS")
		)
		(fp_line
			(start -1.988058 2.750058)
			(end 2.750058 2.750058)
			(stroke
				(width 0.1524)
				(type default)
			)
			(layer "F.SilkS")
		)
		(fp_line
			(start -1.988058 -2.750058)
			(end -2.750058 -1.988058)
			(stroke
				(width 0.1524)
				(type default)
			)
			(layer "F.SilkS")
		)
		(fp_line
			(start -2.750058 1.988058)
			(end -1.988058 2.750058)
			(stroke
				(width 0.1524)
				(type default)
			)
			(layer "F.SilkS")
		)
		(fp_line
			(start -2.750058 0.9398)
			(end -2.750058 1.988058)
			(stroke
				(width 0.1524)
				(type default)
			)
			(layer "F.SilkS")
		)
		(fp_line
			(start -2.750058 -1.988058)
			(end -2.750058 -0.9398)
			(stroke
				(width 0.1524)
				(type default)
			)
			(layer "F.SilkS")
		)
		(fp_line
			(start 2.750058 2.750058)
			(end 2.750058 -2.750058)
			(stroke
				(width 0.1)
				(type default)
			)
			(layer "F.Fab")
		)
		(fp_line
			(start 2.750058 -2.750058)
			(end -2.750058 -2.750058)
			(stroke
				(width 0.1)
				(type default)
			)
			(layer "F.Fab")
		)
		(fp_line
			(start -2.750058 2.750058)
			(end 2.750058 2.750058)
			(stroke
				(width 0.1)
				(type default)
			)
			(layer "F.Fab")
		)
		(fp_line
			(start -2.750058 -2.750058)
			(end -2.750058 2.750058)
			(stroke
				(width 0.1)
				(type default)
			)
			(layer "F.Fab")
		)
		(pad "1" smd rect
			(at -2.199894 0 270)
			(size 1.6002 3.0226)
			(layers "F.Cu" "F.Mask" "F.Paste")
			(net "SW_P12V_AUX_P0V9_RETIMER_CPU0_FLT")
		)
		(pad "2" smd rect
			(at 2.199894 0 270)
			(size 1.6002 3.0226)
			(layers "F.Cu" "F.Mask" "F.Paste")
			(net "GND")
		)
	)
	(footprint ""
		(layer "F.Cu")
		(at 319.940178 -39.55542)
		(property "Reference" "C2194"
			(at 0 0 0)
			(layer "F.SilkS")
			(hide yes)
			(effects
				(font
					(size 1.27 1.27)
				)
			)
		)
		(property "Value" ""
			(at 0 0 0)
			(layer "F.Fab")
			(effects
				(font
					(size 1.27 1.27)
				)
			)
		)
		(duplicate_pad_numbers_are_jumpers no)
		(fp_line
			(start -0.7874 -0.4064)
			(end 0.7874 -0.4064)
			(stroke
				(width 0.1524)
				(type default)
			)
			(layer "F.SilkS")
		)
		(fp_line
			(start -0.7874 0.4064)
			(end -0.7874 -0.4064)
			(stroke
				(width 0.1524)
				(type default)
			)
			(layer "F.SilkS")
		)
		(fp_line
			(start 0.7874 -0.4064)
			(end 0.7874 0.4064)
			(stroke
				(width 0.1524)
				(type default)
			)
			(layer "F.SilkS")
		)
		(fp_line
			(start 0.7874 0.4064)
			(end -0.7874 0.4064)
			(stroke
				(width 0.1524)
				(type default)
			)
			(layer "F.SilkS")
		)
		(fp_line
			(start -0.67945 -0.305054)
			(end -0.12065 -0.305054)
			(stroke
				(width 0.1)
				(type default)
			)
			(layer "F.Fab")
		)
		(fp_line
			(start -0.67945 0.3048)
			(end -0.67945 -0.305054)
			(stroke
				(width 0.1)
				(type default)
			)
			(layer "F.Fab")
		)
		(fp_line
			(start -0.12065 -0.305054)
			(end -0.12065 -0.2794)
			(stroke
				(width 0.1)
				(type default)
			)
			(layer "F.Fab")
		)
		(fp_line
			(start -0.12065 -0.2794)
			(end 0.12065 -0.2794)
			(stroke
				(width 0.1)
				(type default)
			)
			(layer "F.Fab")
		)
		(fp_line
			(start -0.12065 0.2794)
			(end -0.12065 0.3048)
			(stroke
				(width 0.1)
				(type default)
			)
			(layer "F.Fab")
		)
		(fp_line
			(start -0.12065 0.3048)
			(end -0.67945 0.3048)
			(stroke
				(width 0.1)
				(type default)
			)
			(layer "F.Fab")
		)
		(fp_line
			(start 0.120396 0.2794)
			(end -0.12065 0.2794)
			(stroke
				(width 0.1)
				(type default)
			)
			(layer "F.Fab")
		)
		(fp_line
			(start 0.120396 0.3048)
			(end 0.120396 0.2794)
			(stroke
				(width 0.1)
				(type default)
			)
			(layer "F.Fab")
		)
		(fp_line
			(start 0.12065 -0.3048)
			(end 0.67945 -0.3048)
			(stroke
				(width 0.1)
				(type default)
			)
			(layer "F.Fab")
		)
		(fp_line
			(start 0.12065 -0.2794)
			(end 0.12065 -0.3048)
			(stroke
				(width 0.1)
				(type default)
			)
			(layer "F.Fab")
		)
		(fp_line
			(start 0.67945 -0.3048)
			(end 0.67945 0.3048)
			(stroke
				(width 0.1)
				(type default)
			)
			(layer "F.Fab")
		)
		(fp_line
			(start 0.67945 0.3048)
			(end 0.120396 0.3048)
			(stroke
				(width 0.1)
				(type default)
			)
			(layer "F.Fab")
		)
		(pad "1" smd circle
			(at -0.40005 0)
			(size 0 0)
			(layers "F.Cu" "F.Mask" "F.Paste")
			(net "P12V_E1S_0_ISENSE_TIC")
		)
		(pad "2" smd circle
			(at 0.40005 0)
			(size 0 0)
			(layers "F.Cu" "F.Mask" "F.Paste")
			(net "GND")
		)
	)
	(footprint ""
		(layer "F.Cu")
		(at 164.142674 -38.493954 90)
		(property "Reference" "R2489"
			(at 0 0 90)
			(layer "F.SilkS")
			(hide yes)
			(effects
				(font
					(size 1.27 1.27)
				)
			)
		)
		(property "Value" ""
			(at 0 0 90)
			(layer "F.Fab")
			(effects
				(font
					(size 1.27 1.27)
				)
			)
		)
		(duplicate_pad_numbers_are_jumpers no)
		(fp_line
			(start 0.7874 -0.4064)
			(end 0.7874 0.4064)
			(stroke
				(width 0.1524)
				(type default)
			)
			(layer "F.SilkS")
		)
		(fp_line
			(start -0.7874 -0.4064)
			(end 0.7874 -0.4064)
			(stroke
				(width 0.1524)
				(type default)
			)
			(layer "F.SilkS")
		)
		(fp_line
			(start 0.7874 0.4064)
			(end -0.7874 0.4064)
			(stroke
				(width 0.1524)
				(type default)
			)
			(layer "F.SilkS")
		)
		(fp_line
			(start -0.7874 0.4064)
			(end -0.7874 -0.4064)
			(stroke
				(width 0.1524)
				(type default)
			)
			(layer "F.SilkS")
		)
		(fp_line
			(start -0.12065 -0.305054)
			(end -0.12065 -0.2794)
			(stroke
				(width 0.1)
				(type default)
			)
			(layer "F.Fab")
		)
		(fp_line
			(start -0.67945 -0.305054)
			(end -0.12065 -0.305054)
			(stroke
				(width 0.1)
				(type default)
			)
			(layer "F.Fab")
		)
		(fp_line
			(start 0.67945 -0.3048)
			(end 0.67945 0.3048)
			(stroke
				(width 0.1)
				(type default)
			)
			(layer "F.Fab")
		)
		(fp_line
			(start 0.12065 -0.3048)
			(end 0.67945 -0.3048)
			(stroke
				(width 0.1)
				(type default)
			)
			(layer "F.Fab")
		)
		(fp_line
			(start 0.12065 -0.2794)
			(end 0.12065 -0.3048)
			(stroke
				(width 0.1)
				(type default)
			)
			(layer "F.Fab")
		)
		(fp_line
			(start -0.12065 -0.2794)
			(end 0.12065 -0.2794)
			(stroke
				(width 0.1)
				(type default)
			)
			(layer "F.Fab")
		)
		(fp_line
			(start 0.120396 0.2794)
			(end -0.12065 0.2794)
			(stroke
				(width 0.1)
				(type default)
			)
			(layer "F.Fab")
		)
		(fp_line
			(start -0.12065 0.2794)
			(end -0.12065 0.3048)
			(stroke
				(width 0.1)
				(type default)
			)
			(layer "F.Fab")
		)
		(fp_line
			(start 0.67945 0.3048)
			(end 0.120396 0.3048)
			(stroke
				(width 0.1)
				(type default)
			)
			(layer "F.Fab")
		)
		(fp_line
			(start 0.120396 0.3048)
			(end 0.120396 0.2794)
			(stroke
				(width 0.1)
				(type default)
			)
			(layer "F.Fab")
		)
		(fp_line
			(start -0.12065 0.3048)
			(end -0.67945 0.3048)
			(stroke
				(width 0.1)
				(type default)
			)
			(layer "F.Fab")
		)
		(fp_line
			(start -0.67945 0.3048)
			(end -0.67945 -0.305054)
			(stroke
				(width 0.1)
				(type default)
			)
			(layer "F.Fab")
		)
		(pad "1" smd circle
			(at -0.40005 0 90)
			(size 0 0)
			(layers "F.Cu" "F.Mask" "F.Paste")
			(net "IRQ_LVC3_WAKE_BUF_N")
		)
		(pad "2" smd circle
			(at 0.40005 0 90)
			(size 0 0)
			(layers "F.Cu" "F.Mask" "F.Paste")
			(net "IRQ_OCP_SFF_WAKE_BUF_N")
		)
	)
)
